(kicad_pcb
	(version 20260206)
	(generator "pcbnew")
	(generator_version "10.0")
	(general
		(thickness 1.6)
		(legacy_teardrops no)
	)
	(paper "A4")
	(title_block
		(title "dpb — 14545-sa.0730WZS0815.brd")
		(comment 1 "Honey Badger (Wiwynn) / footprints 137-143 of 1066")
	)
	(layers
		(0 "F.Cu" signal "TOP")
		(4 "In1.Cu" signal "L2GND")
		(6 "In2.Cu" signal "L3")
		(8 "In3.Cu" signal "L4VCC")
		(10 "In4.Cu" signal "L5VCC")
		(12 "In5.Cu" signal "L6")
		(14 "In6.Cu" signal "L7GND")
		(2 "B.Cu" signal "BOTTOM")
		(9 "F.Adhes" user "F.Adhesive")
		(11 "B.Adhes" user "B.Adhesive")
		(13 "F.Paste" user "Package Geometry/Pastemask Top")
		(15 "B.Paste" user "Package Geometry/Pastemask Bottom")
		(5 "F.SilkS" user "Ref Des/Silkscreen Top")
		(7 "B.SilkS" user "Ref Des/Silkscreen Bottom")
		(1 "F.Mask" user "Board Geometry/Soldermask Top")
		(3 "B.Mask" user "Board Geometry/Soldermask Bottom")
		(17 "Dwgs.User" user "User.Drawings")
		(19 "Cmts.User" user "User.Comments")
		(21 "Eco1.User" user "User.Eco1")
		(23 "Eco2.User" user "User.Eco2")
		(25 "Edge.Cuts" user "Board Geometry/Outline")
		(27 "Margin" user)
		(31 "F.CrtYd" user "Package Geometry/Place Bound Top")
		(29 "B.CrtYd" user "Package Geometry/Place Bound Bottom")
		(35 "F.Fab" user "Ref Des/Assembly Top")
		(33 "B.Fab" user "Ref Des/Assembly Bottom")
	)
	(footprint ""
		(layer "F.Cu")
		(at 47.116746 -211.864702 -90)
		(property "Reference" "Q26"
			(at 0 0 270)
			(layer "F.SilkS")
			(hide yes)
			(effects
				(font
					(size 1.27 1.27)
				)
			)
		)
		(property "Value" "2N7002DW-7F-GP"
			(at -2.3622 -8.2042 270)
			(unlocked yes)
			(layer "F.Fab")
			(hide yes)
			(effects
				(font
					(size 1.016 1.016)
					(thickness 0.1524)
				)
			)
		)
		(property "Device Type" "SOT-363H44"
			(at -2.3622 -10.1092 270)
			(unlocked yes)
			(layer "F.Fab")
			(hide yes)
			(effects
				(font
					(size 1.016 1.016)
					(thickness 0.1524)
				)
			)
		)
		(duplicate_pad_numbers_are_jumpers no)
		(fp_line
			(start -1.4478 1.7018)
			(end 1.4478 1.7018)
			(stroke
				(width 0.1524)
				(type default)
			)
			(layer "F.SilkS")
		)
		(fp_line
			(start 1.4478 1.7018)
			(end 1.4478 -1.7018)
			(stroke
				(width 0.1524)
				(type default)
			)
			(layer "F.SilkS")
		)
		(fp_line
			(start -1.27 1.524)
			(end -1.27 0.6604)
			(stroke
				(width 0.4826)
				(type default)
			)
			(layer "F.SilkS")
		)
		(fp_line
			(start -1.4478 -1.7018)
			(end -1.4478 1.7018)
			(stroke
				(width 0.1524)
				(type default)
			)
			(layer "F.SilkS")
		)
		(fp_line
			(start 1.4478 -1.7018)
			(end -1.4478 -1.7018)
			(stroke
				(width 0.1524)
				(type default)
			)
			(layer "F.SilkS")
		)
		(fp_poly
			(pts
				(xy -1.524 -1.778) (xy 1.524 -1.778) (xy 1.524 1.778) (xy -1.524 1.778)
			)
			(stroke
				(width 0)
				(type default)
			)
			(fill no)
			(layer "F.CrtYd")
		)
		(fp_poly
			(pts
				(xy -1.524 -1.778) (xy 1.524 -1.778) (xy 1.524 1.778) (xy -1.524 1.778)
			)
			(stroke
				(width 0)
				(type default)
			)
			(fill no)
			(layer "F.Fab")
		)
		(pad "1" smd rect
			(at -0.65024 0.9398 270)
			(size 0.4064 1.016)
			(layers "F.Cu" "F.Mask" "F.Paste")
			(net "GND")
		)
		(pad "2" smd rect
			(at 0 0.9398 270)
			(size 0.4064 1.016)
			(layers "F.Cu" "F.Mask" "F.Paste")
			(net "SW_PWR_R_HDD12")
		)
		(pad "3" smd rect
			(at 0.65024 0.9398 270)
			(size 0.4064 1.016)
			(layers "F.Cu" "F.Mask" "F.Paste")
			(net "SW_HDD12_P")
		)
		(pad "4" smd rect
			(at 0.65024 -0.9398 270)
			(size 0.4064 1.016)
			(layers "F.Cu" "F.Mask" "F.Paste")
			(net "GND")
		)
		(pad "5" smd rect
			(at 0 -0.9398 270)
			(size 0.4064 1.016)
			(layers "F.Cu" "F.Mask" "F.Paste")
			(net "SW_HDD12_G")
		)
		(pad "6" smd rect
			(at -0.65024 -0.9398 270)
			(size 0.4064 1.016)
			(layers "F.Cu" "F.Mask" "F.Paste")
			(net "SW_HDD12_R")
		)
	)
	(footprint ""
		(layer "F.Cu")
		(at 84.581746 -189.2427 -90)
		(property "Reference" "R454"
			(at 0 0 270)
			(layer "F.SilkS")
			(hide yes)
			(effects
				(font
					(size 1.27 1.27)
				)
			)
		)
		(property "Value" "4K7R2J-2-GP"
			(at 0.064008 -3.993896 270)
			(unlocked yes)
			(layer "F.Fab")
			(hide yes)
			(effects
				(font
					(size 1.016 1.016)
					(thickness 0.1524)
				)
			)
		)
		(property "Device Type" "R402H16"
			(at 0.064008 -5.517896 270)
			(unlocked yes)
			(layer "F.Fab")
			(hide yes)
			(effects
				(font
					(size 1.016 1.016)
					(thickness 0.1524)
				)
			)
		)
		(duplicate_pad_numbers_are_jumpers no)
		(fp_line
			(start -0.508 -0.9398)
			(end -0.508 0.9398)
			(stroke
				(width 0.1524)
				(type default)
			)
			(layer "F.SilkS")
		)
		(fp_line
			(start 0.508 -0.9398)
			(end -0.508 -0.9398)
			(stroke
				(width 0.1524)
				(type default)
			)
			(layer "F.SilkS")
		)
		(fp_rect
			(start -0.508 0.9398)
			(end 0.508 -0.9398)
			(stroke
				(width 0)
				(type default)
			)
			(fill no)
			(layer "F.CrtYd")
		)
		(fp_rect
			(start -0.508 0.9398)
			(end 0.508 -0.9398)
			(stroke
				(width 0)
				(type default)
			)
			(fill no)
			(layer "F.Fab")
		)
		(pad "1" smd custom
			(at 0 -0.4445 270)
			(size 0.1397 0.1397)
			(layers "F.Cu" "F.Mask" "F.Paste")
			(net "P3V3")
			(options
				(clearance outline)
				(anchor circle)
			)
			(primitives
				(gr_poly
					(pts
						(arc
							(start -0.1778 -0.2794)
							(mid -0.249642 -0.249642)
							(end -0.2794 -0.1778)
						)
						(arc
							(start -0.2794 0.1778)
							(mid -0.249642 0.249642)
							(end -0.1778 0.2794)
						)
						(arc
							(start 0.1778 0.2794)
							(mid 0.249642 0.249642)
							(end 0.2794 0.1778)
						)
						(arc
							(start 0.2794 -0.1778)
							(mid 0.249642 -0.249642)
							(end 0.1778 -0.2794)
						)
					)
					(width 0)
					(fill yes)
				)
			)
		)
		(pad "2" smd custom
			(at 0 0.4445 270)
			(size 0.1397 0.1397)
			(layers "F.Cu" "F.Mask" "F.Paste")
			(net "SAS_EXP_A_PWR8")
			(options
				(clearance outline)
				(anchor circle)
			)
			(primitives
				(gr_poly
					(pts
						(arc
							(start -0.1778 -0.2794)
							(mid -0.249642 -0.249642)
							(end -0.2794 -0.1778)
						)
						(arc
							(start -0.2794 0.1778)
							(mid -0.249642 0.249642)
							(end -0.1778 0.2794)
						)
						(arc
							(start 0.1778 0.2794)
							(mid 0.249642 0.249642)
							(end 0.2794 0.1778)
						)
						(arc
							(start 0.2794 -0.1778)
							(mid 0.249642 -0.249642)
							(end 0.1778 -0.2794)
						)
					)
					(width 0)
					(fill yes)
				)
			)
		)
	)
	(footprint ""
		(layer "F.Cu")
		(at 218.465146 -348.5388 90)
		(property "Reference" "R489"
			(at 0 0 90)
			(layer "F.SilkS")
			(hide yes)
			(effects
				(font
					(size 1.27 1.27)
				)
			)
		)
		(property "Value" "1KR2F-3-GP"
			(at 0.064008 -3.993896 90)
			(unlocked yes)
			(layer "F.Fab")
			(hide yes)
			(effects
				(font
					(size 1.016 1.016)
					(thickness 0.1524)
				)
			)
		)
		(property "Device Type" "R402H16"
			(at 0.064008 -5.517896 90)
			(unlocked yes)
			(layer "F.Fab")
			(hide yes)
			(effects
				(font
					(size 1.016 1.016)
					(thickness 0.1524)
				)
			)
		)
		(duplicate_pad_numbers_are_jumpers no)
		(fp_line
			(start 0.508 -0.9398)
			(end -0.508 -0.9398)
			(stroke
				(width 0.1524)
				(type default)
			)
			(layer "F.SilkS")
		)
		(fp_line
			(start -0.508 -0.9398)
			(end -0.508 0.9398)
			(stroke
				(width 0.1524)
				(type default)
			)
			(layer "F.SilkS")
		)
		(fp_rect
			(start -0.508 0.9398)
			(end 0.508 -0.9398)
			(stroke
				(width 0)
				(type default)
			)
			(fill no)
			(layer "F.CrtYd")
		)
		(fp_rect
			(start -0.508 0.9398)
			(end 0.508 -0.9398)
			(stroke
				(width 0)
				(type default)
			)
			(fill no)
			(layer "F.Fab")
		)
		(pad "1" smd custom
			(at 0 -0.4445 90)
			(size 0.1397 0.1397)
			(layers "F.Cu" "F.Mask" "F.Paste")
			(net "FLT_HDD1_B")
			(options
				(clearance outline)
				(anchor circle)
			)
			(primitives
				(gr_poly
					(pts
						(arc
							(start -0.1778 -0.2794)
							(mid -0.249642 -0.249642)
							(end -0.2794 -0.1778)
						)
						(arc
							(start -0.2794 0.1778)
							(mid -0.249642 0.249642)
							(end -0.1778 0.2794)
						)
						(arc
							(start 0.1778 0.2794)
							(mid 0.249642 0.249642)
							(end 0.2794 0.1778)
						)
						(arc
							(start 0.2794 -0.1778)
							(mid 0.249642 -0.249642)
							(end 0.1778 -0.2794)
						)
					)
					(width 0)
					(fill yes)
				)
			)
		)
		(pad "2" smd custom
			(at 0 0.4445 90)
			(size 0.1397 0.1397)
			(layers "F.Cu" "F.Mask" "F.Paste")
			(net "FLT_HDD1_DRIVE")
			(options
				(clearance outline)
				(anchor circle)
			)
			(primitives
				(gr_poly
					(pts
						(arc
							(start -0.1778 -0.2794)
							(mid -0.249642 -0.249642)
							(end -0.2794 -0.1778)
						)
						(arc
							(start -0.2794 0.1778)
							(mid -0.249642 0.249642)
							(end -0.1778 0.2794)
						)
						(arc
							(start 0.1778 0.2794)
							(mid 0.249642 0.249642)
							(end 0.2794 0.1778)
						)
						(arc
							(start 0.2794 -0.1778)
							(mid 0.249642 -0.249642)
							(end 0.1778 -0.2794)
						)
					)
					(width 0)
					(fill yes)
				)
			)
		)
	)
	(footprint ""
		(layer "F.Cu")
		(at 214.743284 -175.560228 -90)
		(property "Reference" "R151"
			(at 0 0 270)
			(layer "F.SilkS")
			(hide yes)
			(effects
				(font
					(size 1.27 1.27)
				)
			)
		)
		(property "Value" "2R2010J-1-GP"
			(at 0.254 -8.0772 270)
			(unlocked yes)
			(layer "F.Fab")
			(hide yes)
			(effects
				(font
					(size 1.016 1.016)
					(thickness 0.1524)
				)
			)
		)
		(property "Device Type" "R2010H28"
			(at 0.254 -9.6774 270)
			(unlocked yes)
			(layer "F.Fab")
			(hide yes)
			(effects
				(font
					(size 1.016 1.016)
					(thickness 0.1524)
				)
			)
		)
		(duplicate_pad_numbers_are_jumpers no)
		(fp_line
			(start -1.651 3.302)
			(end 1.651 3.302)
			(stroke
				(width 0.1524)
				(type default)
			)
			(layer "F.SilkS")
		)
		(fp_line
			(start 1.651 3.302)
			(end 1.651 -3.302)
			(stroke
				(width 0.1524)
				(type default)
			)
			(layer "F.SilkS")
		)
		(fp_line
			(start -1.651 -3.302)
			(end -1.651 3.302)
			(stroke
				(width 0.1524)
				(type default)
			)
			(layer "F.SilkS")
		)
		(fp_line
			(start 1.651 -3.302)
			(end -1.651 -3.302)
			(stroke
				(width 0.1524)
				(type default)
			)
			(layer "F.SilkS")
		)
		(fp_rect
			(start -1.7272 -3.3782)
			(end 1.7272 3.3782)
			(stroke
				(width 0)
				(type default)
			)
			(fill no)
			(layer "F.CrtYd")
		)
		(fp_poly
			(pts
				(xy 1.7272 3.3782) (xy 1.7272 -3.3782) (xy -1.7272 -3.3782) (xy -1.7272 3.3782)
			)
			(stroke
				(width 0)
				(type default)
			)
			(fill no)
			(layer "F.Fab")
		)
		(pad "1" smd rect
			(at 0 -2.3495 270)
			(size 2.794 1.143)
			(layers "F.Cu" "F.Mask" "F.Paste")
			(net "5V_PRE_3")
		)
		(pad "2" smd rect
			(at 0 2.3495 270)
			(size 2.794 1.143)
			(layers "F.Cu" "F.Mask" "F.Paste")
			(net "P5V_HDD3")
		)
	)
	(footprint ""
		(layer "F.Cu")
		(at 17.500092 -155.839922)
		(property "Reference" "LED14"
			(at 0 0 0)
			(layer "F.SilkS")
			(hide yes)
			(effects
				(font
					(size 1.27 1.27)
				)
			)
		)
		(property "Value" "LED-RB-4-GP"
			(at 5.88899 1.80848 0)
			(unlocked yes)
			(layer "F.Fab")
			(hide yes)
			(effects
				(font
					(size 1.016 1.016)
					(thickness 0.1524)
				)
			)
		)
		(property "Device Type" "LED1613-4PH20"
			(at 5.88899 0.28448 0)
			(unlocked yes)
			(layer "F.Fab")
			(hide yes)
			(effects
				(font
					(size 1.016 1.016)
					(thickness 0.1524)
				)
			)
		)
		(duplicate_pad_numbers_are_jumpers no)
		(fp_line
			(start -1.4478 -0.9652)
			(end 1.4478 -0.9652)
			(stroke
				(width 0.1524)
				(type default)
			)
			(layer "F.SilkS")
		)
		(fp_line
			(start -1.4478 0.9652)
			(end -1.4478 -0.9652)
			(stroke
				(width 0.1524)
				(type default)
			)
			(layer "F.SilkS")
		)
		(fp_line
			(start -1.4478 0.9652)
			(end -1.4478 -0.9652)
			(stroke
				(width 0.508)
				(type default)
			)
			(layer "F.SilkS")
		)
		(fp_line
			(start 1.4478 -0.9652)
			(end 1.4478 0.9652)
			(stroke
				(width 0.1524)
				(type default)
			)
			(layer "F.SilkS")
		)
		(fp_line
			(start 1.4478 0.9652)
			(end -1.4478 0.9652)
			(stroke
				(width 0.1524)
				(type default)
			)
			(layer "F.SilkS")
		)
		(fp_rect
			(start -0.8001 0.6477)
			(end 0.8001 -0.6477)
			(stroke
				(width 0)
				(type default)
			)
			(fill no)
			(layer "F.CrtYd")
		)
		(fp_poly
			(pts
				(xy -1.7018 1.2192) (xy -1.7018 -0.06223) (xy -0.8001 -0.06223) (xy -0.8001 0.6477) (xy 0.8001 0.6477)
				(xy 0.8001 -0.6477) (xy -0.8001 -0.6477) (xy -0.8001 -0.0635) (xy -1.7018 -0.0635) (xy -1.7018 -1.2192)
				(xy 1.7018 -1.2192) (xy 1.7018 1.2192)
			)
			(stroke
				(width 0)
				(type default)
			)
			(fill no)
			(layer "F.CrtYd")
		)
		(fp_rect
			(start -1.7018 1.2192)
			(end 1.7018 -1.2192)
			(stroke
				(width 0)
				(type default)
			)
			(fill no)
			(layer "F.Fab")
		)
		(pad "1" smd rect
			(at -0.73025 0.4064)
			(size 0.9144 0.6096)
			(layers "F.Cu" "F.Mask" "F.Paste")
			(net "DRV_ACT_NET13")
		)
		(pad "2" smd rect
			(at -0.73025 -0.4064)
			(size 0.9144 0.6096)
			(layers "F.Cu" "F.Mask" "F.Paste")
			(net "FLT_NET_HDD13")
		)
		(pad "3" smd rect
			(at 0.73025 -0.4064)
			(size 0.9144 0.6096)
			(layers "F.Cu" "F.Mask" "F.Paste")
			(net "FLT_HDD13")
		)
		(pad "4" smd rect
			(at 0.73025 0.4064)
			(size 0.9144 0.6096)
			(layers "F.Cu" "F.Mask" "F.Paste")
			(net "DRV_ACT_13")
		)
	)
	(footprint ""
		(layer "F.Cu")
		(at 80.4418 -92.7608 -90)
		(property "Reference" "R417"
			(at 0 0 270)
			(layer "F.SilkS")
			(hide yes)
			(effects
				(font
					(size 1.27 1.27)
				)
			)
		)
		(property "Value" "0R2J-2-GP"
			(at 0.064008 -3.993896 270)
			(unlocked yes)
			(layer "F.Fab")
			(hide yes)
			(effects
				(font
					(size 1.016 1.016)
					(thickness 0.1524)
				)
			)
		)
		(property "Device Type" "R402H16"
			(at 0.064008 -5.517896 270)
			(unlocked yes)
			(layer "F.Fab")
			(hide yes)
			(effects
				(font
					(size 1.016 1.016)
					(thickness 0.1524)
				)
			)
		)
		(duplicate_pad_numbers_are_jumpers no)
		(fp_line
			(start -0.508 -0.9398)
			(end -0.508 0.9398)
			(stroke
				(width 0.1524)
				(type default)
			)
			(layer "F.SilkS")
		)
		(fp_line
			(start 0.508 -0.9398)
			(end -0.508 -0.9398)
			(stroke
				(width 0.1524)
				(type default)
			)
			(layer "F.SilkS")
		)
		(fp_rect
			(start -0.508 0.9398)
			(end 0.508 -0.9398)
			(stroke
				(width 0)
				(type default)
			)
			(fill no)
			(layer "F.CrtYd")
		)
		(fp_rect
			(start -0.508 0.9398)
			(end 0.508 -0.9398)
			(stroke
				(width 0)
				(type default)
			)
			(fill no)
			(layer "F.Fab")
		)
		(pad "1" smd custom
			(at 0 -0.4445 270)
			(size 0.1397 0.1397)
			(layers "F.Cu" "F.Mask" "F.Paste")
			(net "SW_HDD9_G")
			(options
				(clearance outline)
				(anchor circle)
			)
			(primitives
				(gr_poly
					(pts
						(arc
							(start -0.1778 -0.2794)
							(mid -0.249642 -0.249642)
							(end -0.2794 -0.1778)
						)
						(arc
							(start -0.2794 0.1778)
							(mid -0.249642 0.249642)
							(end -0.1778 0.2794)
						)
						(arc
							(start 0.1778 0.2794)
							(mid 0.249642 0.249642)
							(end 0.2794 0.1778)
						)
						(arc
							(start 0.2794 -0.1778)
							(mid 0.249642 -0.249642)
							(end 0.1778 -0.2794)
						)
					)
					(width 0)
					(fill yes)
				)
			)
		)
		(pad "2" smd custom
			(at 0 0.4445 270)
			(size 0.1397 0.1397)
			(layers "F.Cu" "F.Mask" "F.Paste")
			(net "SW_HDD9_R")
			(options
				(clearance outline)
				(anchor circle)
			)
			(primitives
				(gr_poly
					(pts
						(arc
							(start -0.1778 -0.2794)
							(mid -0.249642 -0.249642)
							(end -0.2794 -0.1778)
						)
						(arc
							(start -0.2794 0.1778)
							(mid -0.249642 0.249642)
							(end -0.1778 0.2794)
						)
						(arc
							(start 0.1778 0.2794)
							(mid 0.249642 0.249642)
							(end 0.2794 0.1778)
						)
						(arc
							(start 0.2794 -0.1778)
							(mid 0.249642 -0.249642)
							(end 0.1778 -0.2794)
						)
					)
					(width 0)
					(fill yes)
				)
			)
		)
	)
	(footprint ""
		(layer "F.Cu")
		(at 51.689 -208.534 180)
		(property "Reference" "R560"
			(at 0 0 180)
			(layer "F.SilkS")
			(hide yes)
			(effects
				(font
					(size 1.27 1.27)
				)
			)
		)
		(property "Value" "200KR2F-L-GP"
			(at 0.064008 -3.993896 180)
			(unlocked yes)
			(layer "F.Fab")
			(hide yes)
			(effects
				(font
					(size 1.016 1.016)
					(thickness 0.1524)
				)
			)
		)
		(property "Device Type" "R402H16"
			(at 0.064008 -5.517896 180)
			(unlocked yes)
			(layer "F.Fab")
			(hide yes)
			(effects
				(font
					(size 1.016 1.016)
					(thickness 0.1524)
				)
			)
		)
		(duplicate_pad_numbers_are_jumpers no)
		(fp_line
			(start 0.508 -0.9398)
			(end -0.508 -0.9398)
			(stroke
				(width 0.1524)
				(type default)
			)
			(layer "F.SilkS")
		)
		(fp_line
			(start -0.508 -0.9398)
			(end -0.508 0.9398)
			(stroke
				(width 0.1524)
				(type default)
			)
			(layer "F.SilkS")
		)
		(fp_rect
			(start -0.508 0.9398)
			(end 0.508 -0.9398)
			(stroke
				(width 0)
				(type default)
			)
			(fill no)
			(layer "F.CrtYd")
		)
		(fp_rect
			(start -0.508 0.9398)
			(end 0.508 -0.9398)
			(stroke
				(width 0)
				(type default)
			)
			(fill no)
			(layer "F.Fab")
		)
		(pad "1" smd custom
			(at 0 -0.4445 180)
			(size 0.1397 0.1397)
			(layers "F.Cu" "F.Mask" "F.Paste")
			(net "SW_HDD12_R")
			(options
				(clearance outline)
				(anchor circle)
			)
			(primitives
				(gr_poly
					(pts
						(arc
							(start -0.1778 -0.2794)
							(mid -0.249642 -0.249642)
							(end -0.2794 -0.1778)
						)
						(arc
							(start -0.2794 0.1778)
							(mid -0.249642 0.249642)
							(end -0.1778 0.2794)
						)
						(arc
							(start 0.1778 0.2794)
							(mid 0.249642 0.249642)
							(end 0.2794 0.1778)
						)
						(arc
							(start 0.2794 -0.1778)
							(mid 0.249642 -0.249642)
							(end 0.1778 -0.2794)
						)
					)
					(width 0)
					(fill yes)
				)
			)
		)
		(pad "2" smd custom
			(at 0 0.4445 180)
			(size 0.1397 0.1397)
			(layers "F.Cu" "F.Mask" "F.Paste")
			(net "SW_HDD12_N")
			(options
				(clearance outline)
				(anchor circle)
			)
			(primitives
				(gr_poly
					(pts
						(arc
							(start -0.1778 -0.2794)
							(mid -0.249642 -0.249642)
							(end -0.2794 -0.1778)
						)
						(arc
							(start -0.2794 0.1778)
							(mid -0.249642 0.249642)
							(end -0.1778 0.2794)
						)
						(arc
							(start 0.1778 0.2794)
							(mid 0.249642 0.249642)
							(end 0.2794 0.1778)
						)
						(arc
							(start 0.2794 -0.1778)
							(mid 0.249642 -0.249642)
							(end 0.1778 -0.2794)
						)
					)
					(width 0)
					(fill yes)
				)
			)
		)
	)
)
